(kicad_pcb
	(version 20260206)
	(generator "pcbnew")
	(generator_version "10.0")
	(general
		(thickness 1.6)
		(legacy_teardrops no)
	)
	(paper "A4")
	(title_block
		(title "Bryce Canyon_R.DPB_16317-1_OCP.brd")
		(comment 1 "Bryce Canyon / footprints 1255-1261 of 2099")
	)
	(layers
		(0 "F.Cu" signal "TOP")
		(4 "In1.Cu" signal "L2GND")
		(6 "In2.Cu" signal "L3")
		(8 "In3.Cu" signal "L4VCC")
		(10 "In4.Cu" signal "L5VCC")
		(12 "In5.Cu" signal "L6")
		(14 "In6.Cu" signal "L7GND")
		(2 "B.Cu" signal "BOTTOM")
		(9 "F.Adhes" user "F.Adhesive")
		(11 "B.Adhes" user "B.Adhesive")
		(13 "F.Paste" user "Package Geometry/Pastemask Top")
		(15 "B.Paste" user "Package Geometry/Pastemask Bottom")
		(5 "F.SilkS" user "Ref Des/Silkscreen Top")
		(7 "B.SilkS" user "Ref Des/Silkscreen Bottom")
		(1 "F.Mask" user "Board Geometry/Soldermask Top")
		(3 "B.Mask" user "Board Geometry/Soldermask Bottom")
		(17 "Dwgs.User" user "User.Drawings")
		(19 "Cmts.User" user "User.Comments")
		(21 "Eco1.User" user "User.Eco1")
		(23 "Eco2.User" user "User.Eco2")
		(25 "Edge.Cuts" user "Board Geometry/Outline")
		(27 "Margin" user)
		(31 "F.CrtYd" user "Package Geometry/Place Bound Top")
		(29 "B.CrtYd" user "Package Geometry/Place Bound Bottom")
		(35 "F.Fab" user "Ref Des/Assembly Top")
		(33 "B.Fab" user "Ref Des/Assembly Bottom")
	)
	(footprint ""
		(layer "F.Cu")
		(at 477.647 -11.176)
		(property "Reference" "R883"
			(at 0 0 0)
			(layer "F.SilkS")
			(hide yes)
			(effects
				(font
					(size 1.27 1.27)
				)
			)
		)
		(property "Value" "1KR2F-3-GP"
			(at 0.064008 -3.993896 0)
			(unlocked yes)
			(layer "F.Fab")
			(hide yes)
			(effects
				(font
					(size 1.016 1.016)
					(thickness 0.1524)
				)
			)
		)
		(property "Device Type" "R402H16"
			(at 0.064008 -5.517896 0)
			(unlocked yes)
			(layer "F.Fab")
			(hide yes)
			(effects
				(font
					(size 1.016 1.016)
					(thickness 0.1524)
				)
			)
		)
		(duplicate_pad_numbers_are_jumpers no)
		(fp_line
			(start -0.508 -0.9398)
			(end -0.508 0.9398)
			(stroke
				(width 0.1524)
				(type default)
			)
			(layer "F.SilkS")
		)
		(fp_line
			(start 0.508 -0.9398)
			(end -0.508 -0.9398)
			(stroke
				(width 0.1524)
				(type default)
			)
			(layer "F.SilkS")
		)
		(fp_rect
			(start -0.508 0.9398)
			(end 0.508 -0.9398)
			(stroke
				(width 0)
				(type default)
			)
			(fill no)
			(layer "F.CrtYd")
		)
		(fp_rect
			(start -0.508 0.9398)
			(end 0.508 -0.9398)
			(stroke
				(width 0)
				(type default)
			)
			(fill no)
			(layer "F.Fab")
		)
		(pad "1" smd custom
			(at 0 -0.4445)
			(size 0.1397 0.1397)
			(layers "F.Cu" "F.Mask" "F.Paste")
			(net "P3V3_STBY_B")
			(options
				(clearance outline)
				(anchor circle)
			)
			(primitives
				(gr_poly
					(pts
						(arc
							(start -0.1778 -0.2794)
							(mid -0.249642 -0.249642)
							(end -0.2794 -0.1778)
						)
						(arc
							(start -0.2794 0.1778)
							(mid -0.249642 0.249642)
							(end -0.1778 0.2794)
						)
						(arc
							(start 0.1778 0.2794)
							(mid 0.249642 0.249642)
							(end 0.2794 0.1778)
						)
						(arc
							(start 0.2794 -0.1778)
							(mid 0.249642 -0.249642)
							(end 0.1778 -0.2794)
						)
					)
					(width 0)
					(fill yes)
				)
			)
		)
		(pad "2" smd custom
			(at 0 0.4445)
			(size 0.1397 0.1397)
			(layers "F.Cu" "F.Mask" "F.Paste")
			(net "SW_PWR_R_HDD35")
			(options
				(clearance outline)
				(anchor circle)
			)
			(primitives
				(gr_poly
					(pts
						(arc
							(start -0.1778 -0.2794)
							(mid -0.249642 -0.249642)
							(end -0.2794 -0.1778)
						)
						(arc
							(start -0.2794 0.1778)
							(mid -0.249642 0.249642)
							(end -0.1778 0.2794)
						)
						(arc
							(start 0.1778 0.2794)
							(mid 0.249642 0.249642)
							(end 0.2794 0.1778)
						)
						(arc
							(start 0.2794 -0.1778)
							(mid 0.249642 -0.249642)
							(end 0.1778 -0.2794)
						)
					)
					(width 0)
					(fill yes)
				)
			)
		)
	)
	(footprint ""
		(layer "F.Cu")
		(at 25.974802 -232.16235)
		(property "Reference" "R1097"
			(at 0 0 0)
			(layer "F.SilkS")
			(hide yes)
			(effects
				(font
					(size 1.27 1.27)
				)
			)
		)
		(property "Value" "49K9R2F-L-GP"
			(at 0.064008 -3.993896 0)
			(unlocked yes)
			(layer "F.Fab")
			(hide yes)
			(effects
				(font
					(size 1.016 1.016)
					(thickness 0.1524)
				)
			)
		)
		(property "Device Type" "R402H16"
			(at 0.064008 -5.517896 0)
			(unlocked yes)
			(layer "F.Fab")
			(hide yes)
			(effects
				(font
					(size 1.016 1.016)
					(thickness 0.1524)
				)
			)
		)
		(duplicate_pad_numbers_are_jumpers no)
		(fp_line
			(start -0.508 -0.9398)
			(end -0.508 0.9398)
			(stroke
				(width 0.1524)
				(type default)
			)
			(layer "F.SilkS")
		)
		(fp_line
			(start 0.508 -0.9398)
			(end -0.508 -0.9398)
			(stroke
				(width 0.1524)
				(type default)
			)
			(layer "F.SilkS")
		)
		(fp_rect
			(start -0.508 0.9398)
			(end 0.508 -0.9398)
			(stroke
				(width 0)
				(type default)
			)
			(fill no)
			(layer "F.CrtYd")
		)
		(fp_rect
			(start -0.508 0.9398)
			(end 0.508 -0.9398)
			(stroke
				(width 0)
				(type default)
			)
			(fill no)
			(layer "F.Fab")
		)
		(pad "1" smd custom
			(at 0 -0.4445)
			(size 0.1397 0.1397)
			(layers "F.Cu" "F.Mask" "F.Paste")
			(net "P12V_B")
			(options
				(clearance outline)
				(anchor circle)
			)
			(primitives
				(gr_poly
					(pts
						(arc
							(start -0.1778 -0.2794)
							(mid -0.249642 -0.249642)
							(end -0.2794 -0.1778)
						)
						(arc
							(start -0.2794 0.1778)
							(mid -0.249642 0.249642)
							(end -0.1778 0.2794)
						)
						(arc
							(start 0.1778 0.2794)
							(mid 0.249642 0.249642)
							(end 0.2794 0.1778)
						)
						(arc
							(start 0.2794 -0.1778)
							(mid 0.249642 -0.249642)
							(end 0.1778 -0.2794)
						)
					)
					(width 0)
					(fill yes)
				)
			)
		)
		(pad "2" smd custom
			(at 0 0.4445)
			(size 0.1397 0.1397)
			(layers "F.Cu" "F.Mask" "F.Paste")
			(net "P5V_B_1_EN_R")
			(options
				(clearance outline)
				(anchor circle)
			)
			(primitives
				(gr_poly
					(pts
						(arc
							(start -0.1778 -0.2794)
							(mid -0.249642 -0.249642)
							(end -0.2794 -0.1778)
						)
						(arc
							(start -0.2794 0.1778)
							(mid -0.249642 0.249642)
							(end -0.1778 0.2794)
						)
						(arc
							(start 0.1778 0.2794)
							(mid 0.249642 0.249642)
							(end 0.2794 0.1778)
						)
						(arc
							(start 0.2794 -0.1778)
							(mid 0.249642 -0.249642)
							(end 0.1778 -0.2794)
						)
					)
					(width 0)
					(fill yes)
				)
			)
		)
	)
	(footprint ""
		(layer "F.Cu")
		(at 143.129 -247.65 180)
		(property "Reference" "D4"
			(at 0 0 180)
			(layer "F.SilkS")
			(hide yes)
			(effects
				(font
					(size 1.27 1.27)
				)
			)
		)
		(property "Value" "RB551V30-GP"
			(at 0 -6.7818 180)
			(unlocked yes)
			(layer "F.Fab")
			(hide yes)
			(effects
				(font
					(size 1.016 1.016)
					(thickness 0.1524)
				)
			)
		)
		(property "Device Type" "SOD323AKH38"
			(at 0 -8.6868 180)
			(unlocked yes)
			(layer "F.Fab")
			(hide yes)
			(effects
				(font
					(size 1.016 1.016)
					(thickness 0.1524)
				)
			)
		)
		(duplicate_pad_numbers_are_jumpers no)
		(fp_line
			(start 0.889 2.159)
			(end -0.889 2.159)
			(stroke
				(width 0.1524)
				(type default)
			)
			(layer "F.SilkS")
		)
		(fp_line
			(start 0.889 -1.9304)
			(end 0.889 2.159)
			(stroke
				(width 0.1524)
				(type default)
			)
			(layer "F.SilkS")
		)
		(fp_line
			(start 0.762 2.0574)
			(end -0.762 2.0574)
			(stroke
				(width 0.508)
				(type default)
			)
			(layer "F.SilkS")
		)
		(fp_line
			(start -0.889 2.159)
			(end -0.889 -1.9304)
			(stroke
				(width 0.1524)
				(type default)
			)
			(layer "F.SilkS")
		)
		(fp_line
			(start -0.889 -1.9304)
			(end 0.889 -1.9304)
			(stroke
				(width 0.1524)
				(type default)
			)
			(layer "F.SilkS")
		)
		(fp_rect
			(start -1.016 2.3114)
			(end 1.016 -2.0066)
			(stroke
				(width 0)
				(type default)
			)
			(fill no)
			(layer "F.CrtYd")
		)
		(fp_poly
			(pts
				(xy -1.016 -2.0066) (xy 1.016 -2.0066) (xy 1.016 2.3114) (xy -1.016 2.3114)
			)
			(stroke
				(width 0)
				(type default)
			)
			(fill no)
			(layer "F.Fab")
		)
		(pad "A" smd rect
			(at 0 -1.143 180)
			(size 0.5588 1.016)
			(layers "F.Cu" "F.Mask" "F.Paste")
			(net "SW_HDD_R4")
		)
		(pad "K" smd rect
			(at 0 1.143 180)
			(size 0.5588 1.016)
			(layers "F.Cu" "F.Mask" "F.Paste")
			(net "SW_HDD_N4")
		)
	)
	(footprint ""
		(layer "F.Cu")
		(at 317.119 -98.171)
		(property "Reference" "R433"
			(at 0 0 0)
			(layer "F.SilkS")
			(hide yes)
			(effects
				(font
					(size 1.27 1.27)
				)
			)
		)
		(property "Value" "91R3F-1-GP"
			(at -0.0254 -2.5146 0)
			(unlocked yes)
			(layer "F.Fab")
			(hide yes)
			(effects
				(font
					(size 1.016 1.016)
					(thickness 0.1524)
				)
			)
		)
		(property "Device Type" "R603H22"
			(at -0.0254 -4.0386 0)
			(unlocked yes)
			(layer "F.Fab")
			(hide yes)
			(effects
				(font
					(size 1.016 1.016)
					(thickness 0.1524)
				)
			)
		)
		(duplicate_pad_numbers_are_jumpers no)
		(fp_line
			(start -0.4826 0)
			(end -0.2032 0)
			(stroke
				(width 0.2032)
				(type default)
			)
			(layer "F.SilkS")
		)
		(fp_line
			(start 0.2032 0)
			(end 0.4826 0)
			(stroke
				(width 0.2032)
				(type default)
			)
			(layer "F.SilkS")
		)
		(fp_rect
			(start -0.5842 1.3335)
			(end 0.5842 -1.3335)
			(stroke
				(width 0)
				(type default)
			)
			(fill no)
			(layer "F.CrtYd")
		)
		(fp_rect
			(start -0.5842 1.3335)
			(end 0.5842 -1.3335)
			(stroke
				(width 0)
				(type default)
			)
			(fill no)
			(layer "F.Fab")
		)
		(pad "1" smd custom
			(at 0 -0.762)
			(size 0.2159 0.2159)
			(layers "F.Cu" "F.Mask" "F.Paste")
			(net "P5V_B_3")
			(options
				(clearance outline)
				(anchor circle)
			)
			(primitives
				(gr_poly
					(pts
						(arc
							(start -0.3302 -0.4318)
							(mid -0.402042 -0.402042)
							(end -0.4318 -0.3302)
						)
						(arc
							(start -0.4318 0.3302)
							(mid -0.402042 0.402042)
							(end -0.3302 0.4318)
						)
						(arc
							(start 0.3302 0.4318)
							(mid 0.402042 0.402042)
							(end 0.4318 0.3302)
						)
						(arc
							(start 0.4318 -0.3302)
							(mid 0.402042 -0.402042)
							(end 0.3302 -0.4318)
						)
					)
					(width 0)
					(fill yes)
				)
			)
		)
		(pad "2" smd custom
			(at 0 0.762)
			(size 0.2159 0.2159)
			(layers "F.Cu" "F.Mask" "F.Paste")
			(net "DRV_ACT_18")
			(options
				(clearance outline)
				(anchor circle)
			)
			(primitives
				(gr_poly
					(pts
						(arc
							(start -0.3302 -0.4318)
							(mid -0.402042 -0.402042)
							(end -0.4318 -0.3302)
						)
						(arc
							(start -0.4318 0.3302)
							(mid -0.402042 0.402042)
							(end -0.3302 0.4318)
						)
						(arc
							(start 0.3302 0.4318)
							(mid 0.402042 0.402042)
							(end 0.4318 0.3302)
						)
						(arc
							(start 0.4318 -0.3302)
							(mid 0.402042 -0.402042)
							(end 0.3302 -0.4318)
						)
					)
					(width 0)
					(fill yes)
				)
			)
		)
	)
	(footprint ""
		(layer "F.Cu")
		(at 256.484374 -228.36505 90)
		(property "Reference" "R165"
			(at 0 0 90)
			(layer "F.SilkS")
			(hide yes)
			(effects
				(font
					(size 1.27 1.27)
				)
			)
		)
		(property "Value" "10KR2F-2-GP"
			(at 0.064008 -3.993896 90)
			(unlocked yes)
			(layer "F.Fab")
			(hide yes)
			(effects
				(font
					(size 1.016 1.016)
					(thickness 0.1524)
				)
			)
		)
		(property "Device Type" "R402H16"
			(at 0.064008 -5.517896 90)
			(unlocked yes)
			(layer "F.Fab")
			(hide yes)
			(effects
				(font
					(size 1.016 1.016)
					(thickness 0.1524)
				)
			)
		)
		(duplicate_pad_numbers_are_jumpers no)
		(fp_line
			(start 0.508 -0.9398)
			(end -0.508 -0.9398)
			(stroke
				(width 0.1524)
				(type default)
			)
			(layer "F.SilkS")
		)
		(fp_line
			(start -0.508 -0.9398)
			(end -0.508 0.9398)
			(stroke
				(width 0.1524)
				(type default)
			)
			(layer "F.SilkS")
		)
		(fp_rect
			(start -0.508 0.9398)
			(end 0.508 -0.9398)
			(stroke
				(width 0)
				(type default)
			)
			(fill no)
			(layer "F.CrtYd")
		)
		(fp_rect
			(start -0.508 0.9398)
			(end 0.508 -0.9398)
			(stroke
				(width 0)
				(type default)
			)
			(fill no)
			(layer "F.Fab")
		)
		(pad "1" smd custom
			(at 0 -0.4445 90)
			(size 0.1397 0.1397)
			(layers "F.Cu" "F.Mask" "F.Paste")
			(net "P5V_B_2_SENSE")
			(options
				(clearance outline)
				(anchor circle)
			)
			(primitives
				(gr_poly
					(pts
						(arc
							(start -0.1778 -0.2794)
							(mid -0.249642 -0.249642)
							(end -0.2794 -0.1778)
						)
						(arc
							(start -0.2794 0.1778)
							(mid -0.249642 0.249642)
							(end -0.1778 0.2794)
						)
						(arc
							(start 0.1778 0.2794)
							(mid 0.249642 0.249642)
							(end 0.2794 0.1778)
						)
						(arc
							(start 0.2794 -0.1778)
							(mid 0.249642 -0.249642)
							(end 0.1778 -0.2794)
						)
					)
					(width 0)
					(fill yes)
				)
			)
		)
		(pad "2" smd custom
			(at 0 0.4445 90)
			(size 0.1397 0.1397)
			(layers "F.Cu" "F.Mask" "F.Paste")
			(net "GND")
			(options
				(clearance outline)
				(anchor circle)
			)
			(primitives
				(gr_poly
					(pts
						(arc
							(start -0.1778 -0.2794)
							(mid -0.249642 -0.249642)
							(end -0.2794 -0.1778)
						)
						(arc
							(start -0.2794 0.1778)
							(mid -0.249642 0.249642)
							(end -0.1778 0.2794)
						)
						(arc
							(start 0.1778 0.2794)
							(mid 0.249642 0.249642)
							(end 0.2794 0.1778)
						)
						(arc
							(start 0.2794 -0.1778)
							(mid 0.249642 -0.249642)
							(end 0.1778 -0.2794)
						)
					)
					(width 0)
					(fill yes)
				)
			)
		)
	)
	(footprint ""
		(layer "F.Cu")
		(at 336.7151 -357.7336 90)
		(property "Reference" "R148"
			(at 0 0 90)
			(layer "F.SilkS")
			(hide yes)
			(effects
				(font
					(size 1.27 1.27)
				)
			)
		)
		(property "Value" "300KR2F-GP"
			(at 0.064008 -3.993896 90)
			(unlocked yes)
			(layer "F.Fab")
			(hide yes)
			(effects
				(font
					(size 1.016 1.016)
					(thickness 0.1524)
				)
			)
		)
		(property "Device Type" "R402H16"
			(at 0.064008 -5.517896 90)
			(unlocked yes)
			(layer "F.Fab")
			(hide yes)
			(effects
				(font
					(size 1.016 1.016)
					(thickness 0.1524)
				)
			)
		)
		(duplicate_pad_numbers_are_jumpers no)
		(fp_line
			(start 0.508 -0.9398)
			(end -0.508 -0.9398)
			(stroke
				(width 0.1524)
				(type default)
			)
			(layer "F.SilkS")
		)
		(fp_line
			(start -0.508 -0.9398)
			(end -0.508 0.9398)
			(stroke
				(width 0.1524)
				(type default)
			)
			(layer "F.SilkS")
		)
		(fp_rect
			(start -0.508 0.9398)
			(end 0.508 -0.9398)
			(stroke
				(width 0)
				(type default)
			)
			(fill no)
			(layer "F.CrtYd")
		)
		(fp_rect
			(start -0.508 0.9398)
			(end 0.508 -0.9398)
			(stroke
				(width 0)
				(type default)
			)
			(fill no)
			(layer "F.Fab")
		)
		(pad "1" smd custom
			(at 0 -0.4445 90)
			(size 0.1397 0.1397)
			(layers "F.Cu" "F.Mask" "F.Paste")
			(net "GATE_FAN2_R")
			(options
				(clearance outline)
				(anchor circle)
			)
			(primitives
				(gr_poly
					(pts
						(arc
							(start -0.1778 -0.2794)
							(mid -0.249642 -0.249642)
							(end -0.2794 -0.1778)
						)
						(arc
							(start -0.2794 0.1778)
							(mid -0.249642 0.249642)
							(end -0.1778 0.2794)
						)
						(arc
							(start 0.1778 0.2794)
							(mid 0.249642 0.249642)
							(end 0.2794 0.1778)
						)
						(arc
							(start 0.2794 -0.1778)
							(mid 0.249642 -0.249642)
							(end 0.1778 -0.2794)
						)
					)
					(width 0)
					(fill yes)
				)
			)
		)
		(pad "2" smd custom
			(at 0 0.4445 90)
			(size 0.1397 0.1397)
			(layers "F.Cu" "F.Mask" "F.Paste")
			(net "P12V_IN")
			(options
				(clearance outline)
				(anchor circle)
			)
			(primitives
				(gr_poly
					(pts
						(arc
							(start -0.1778 -0.2794)
							(mid -0.249642 -0.249642)
							(end -0.2794 -0.1778)
						)
						(arc
							(start -0.2794 0.1778)
							(mid -0.249642 0.249642)
							(end -0.1778 0.2794)
						)
						(arc
							(start 0.1778 0.2794)
							(mid 0.249642 0.249642)
							(end 0.2794 0.1778)
						)
						(arc
							(start 0.2794 -0.1778)
							(mid 0.249642 -0.249642)
							(end 0.1778 -0.2794)
						)
					)
					(width 0)
					(fill yes)
				)
			)
		)
	)
	(footprint ""
		(layer "F.Cu")
		(at 118.872 -275.463 180)
		(property "Reference" "C76"
			(at 0 0 180)
			(layer "F.SilkS")
			(hide yes)
			(effects
				(font
					(size 1.27 1.27)
				)
			)
		)
		(property "Value" "SC1U25V3KX-GP"
			(at 0 -2.8194 180)
			(unlocked yes)
			(layer "F.Fab")
			(hide yes)
			(effects
				(font
					(size 1.016 1.016)
					(thickness 0.1524)
				)
			)
		)
		(property "Device Type" "C603H36"
			(at 0 -4.3434 180)
			(unlocked yes)
			(layer "F.Fab")
			(hide yes)
			(effects
				(font
					(size 1.016 1.016)
					(thickness 0.1524)
				)
			)
		)
		(duplicate_pad_numbers_are_jumpers no)
		(fp_line
			(start 0.508 0)
			(end -0.508 0)
			(stroke
				(width 0.2032)
				(type default)
			)
			(layer "F.SilkS")
		)
		(fp_rect
			(start -0.5842 1.3335)
			(end 0.5842 -1.3335)
			(stroke
				(width 0)
				(type default)
			)
			(fill no)
			(layer "F.CrtYd")
		)
		(fp_rect
			(start -0.5842 1.3335)
			(end 0.5842 -1.3335)
			(stroke
				(width 0)
				(type default)
			)
			(fill no)
			(layer "F.Fab")
		)
		(pad "1" smd custom
			(at 0 -0.762 180)
			(size 0.2159 0.2159)
			(layers "F.Cu" "F.Mask" "F.Paste")
			(net "P12V_HDD3")
			(options
				(clearance outline)
				(anchor circle)
			)
			(primitives
				(gr_poly
					(pts
						(arc
							(start -0.3302 -0.4318)
							(mid -0.402042 -0.402042)
							(end -0.4318 -0.3302)
						)
						(arc
							(start -0.4318 0.3302)
							(mid -0.402042 0.402042)
							(end -0.3302 0.4318)
						)
						(arc
							(start 0.3302 0.4318)
							(mid 0.402042 0.402042)
							(end 0.4318 0.3302)
						)
						(arc
							(start 0.4318 -0.3302)
							(mid 0.402042 -0.402042)
							(end 0.3302 -0.4318)
						)
					)
					(width 0)
					(fill yes)
				)
			)
		)
		(pad "2" smd custom
			(at 0 0.762 180)
			(size 0.2159 0.2159)
			(layers "F.Cu" "F.Mask" "F.Paste")
			(net "GND")
			(options
				(clearance outline)
				(anchor circle)
			)
			(primitives
				(gr_poly
					(pts
						(arc
							(start -0.3302 -0.4318)
							(mid -0.402042 -0.402042)
							(end -0.4318 -0.3302)
						)
						(arc
							(start -0.4318 0.3302)
							(mid -0.402042 0.402042)
							(end -0.3302 0.4318)
						)
						(arc
							(start 0.3302 0.4318)
							(mid 0.402042 0.402042)
							(end 0.4318 0.3302)
						)
						(arc
							(start 0.4318 -0.3302)
							(mid 0.402042 -0.402042)
							(end 0.3302 -0.4318)
						)
					)
					(width 0)
					(fill yes)
				)
			)
		)
	)
)
